FILE_TYPE=LIBRARY_PARTS;
primitive 'K4A8G165WCBCTD';
  pin
    'A0':
      PIN_NUMBER='(P3)';
      INPUT_LOAD='(-0.01,0.01)';
    'A1':
      PIN_NUMBER='(P7)';
      INPUT_LOAD='(-0.01,0.01)';
    'A10||AP':
      PIN_NUMBER='(M3)';
      INPUT_LOAD='(-0.01,0.01)';
    'A11':
      PIN_NUMBER='(T2)';
      INPUT_LOAD='(-0.01,0.01)';
    '-A12||BC':
      PIN_NUMBER='(M7)';
      INPUT_LOAD='(-0.01,0.01)';
    'A13':
      PIN_NUMBER='(T8)';
      INPUT_LOAD='(-0.01,0.01)';
    'A2':
      PIN_NUMBER='(R3)';
      INPUT_LOAD='(-0.01,0.01)';
    'A3':
      PIN_NUMBER='(N7)';
      INPUT_LOAD='(-0.01,0.01)';
    'A4':
      PIN_NUMBER='(N3)';
      INPUT_LOAD='(-0.01,0.01)';
    'A5':
      PIN_NUMBER='(P8)';
      INPUT_LOAD='(-0.01,0.01)';
    'A6':
      PIN_NUMBER='(P2)';
      INPUT_LOAD='(-0.01,0.01)';
    'A7':
      PIN_NUMBER='(R8)';
      INPUT_LOAD='(-0.01,0.01)';
    'A8':
      PIN_NUMBER='(R2)';
      INPUT_LOAD='(-0.01,0.01)';
    'A9':
      PIN_NUMBER='(R7)';
      INPUT_LOAD='(-0.01,0.01)';
    '-ACT':
      PIN_NUMBER='(L3)';
      INPUT_LOAD='(-0.01,0.01)';
    '-ALERT':
      PIN_NUMBER='(P9)';
      BIDIRECTIONAL='TRUE';
      INPUT_LOAD='(-0.01,0.01)';
      OUTPUT_LOAD='(1.0,-1.0)';
    'BA0':
      PIN_NUMBER='(N2)';
      INPUT_LOAD='(-0.01,0.01)';
    'BA1':
      PIN_NUMBER='(N8)';
      INPUT_LOAD='(-0.01,0.01)';
    'BG0':
      PIN_NUMBER='(M2)';
      INPUT_LOAD='(-0.01,0.01)';
    'CAS_N||A15':
      PIN_NUMBER='(M8)';
      INPUT_LOAD='(-0.01,0.01)';
    '-CS':
      PIN_NUMBER='(L7)';
      INPUT_LOAD='(-0.01,0.01)';
    'CKE':
      PIN_NUMBER='(K2)';
      INPUT_LOAD='(-0.01,0.01)';
    'NC1':
      PIN_NUMBER='(T7)';
      OUTPUT_TYPE='(TS,TS)';
      INPUT_LOAD='(-0.01,0.01)';
      OUTPUT_LOAD='(1.0,-1.0)';
    'ODT':
      PIN_NUMBER='(K3)';
      INPUT_LOAD='(-0.01,0.01)';
    '-RAS':
      PIN_NUMBER='(L8)';
      INPUT_LOAD='(-0.01,0.01)';
    'VDD0':
      PIN_NUMBER='(B3)';
      PINUSE='POWER';
      NO_LOAD_CHECK='Both';
      NO_IO_CHECK='Both';
      NO_ASSERT_CHECK='TRUE';
      NO_DIR_CHECK='TRUE';
      ALLOW_CONNECT='TRUE';
    'VDD1':
      PIN_NUMBER='(B9)';
      PINUSE='POWER';
      NO_LOAD_CHECK='Both';
      NO_IO_CHECK='Both';
      NO_ASSERT_CHECK='TRUE';
      NO_DIR_CHECK='TRUE';
      ALLOW_CONNECT='TRUE';
    'VDD2':
      PIN_NUMBER='(D1)';
      PINUSE='POWER';
      NO_LOAD_CHECK='Both';
      NO_IO_CHECK='Both';
      NO_ASSERT_CHECK='TRUE';
      NO_DIR_CHECK='TRUE';
      ALLOW_CONNECT='TRUE';
    'VDD3':
      PIN_NUMBER='(G7)';
      PINUSE='POWER';
      NO_LOAD_CHECK='Both';
      NO_IO_CHECK='Both';
      NO_ASSERT_CHECK='TRUE';
      NO_DIR_CHECK='TRUE';
      ALLOW_CONNECT='TRUE';
    'VDD4':
      PIN_NUMBER='(J1)';
      PINUSE='POWER';
      NO_LOAD_CHECK='Both';
      NO_IO_CHECK='Both';
      NO_ASSERT_CHECK='TRUE';
      NO_DIR_CHECK='TRUE';
      ALLOW_CONNECT='TRUE';
    'VDD5':
      PIN_NUMBER='(J9)';
      PINUSE='POWER';
      NO_LOAD_CHECK='Both';
      NO_IO_CHECK='Both';
      NO_ASSERT_CHECK='TRUE';
      NO_DIR_CHECK='TRUE';
      ALLOW_CONNECT='TRUE';
    'VDD6':
      PIN_NUMBER='(L1)';
      PINUSE='POWER';
      NO_LOAD_CHECK='Both';
      NO_IO_CHECK='Both';
      NO_ASSERT_CHECK='TRUE';
      NO_DIR_CHECK='TRUE';
      ALLOW_CONNECT='TRUE';
    'VDD7':
      PIN_NUMBER='(L9)';
      PINUSE='POWER';
      NO_LOAD_CHECK='Both';
      NO_IO_CHECK='Both';
      NO_ASSERT_CHECK='TRUE';
      NO_DIR_CHECK='TRUE';
      ALLOW_CONNECT='TRUE';
    'VDD8':
      PIN_NUMBER='(R1)';
      PINUSE='POWER';
      NO_LOAD_CHECK='Both';
      NO_IO_CHECK='Both';
      NO_ASSERT_CHECK='TRUE';
      NO_DIR_CHECK='TRUE';
      ALLOW_CONNECT='TRUE';
    'VDD9':
      PIN_NUMBER='(T9)';
      PINUSE='POWER';
      NO_LOAD_CHECK='Both';
      NO_IO_CHECK='Both';
      NO_ASSERT_CHECK='TRUE';
      NO_DIR_CHECK='TRUE';
      ALLOW_CONNECT='TRUE';
    'VDDQ0':
      PIN_NUMBER='(A1)';
      PINUSE='POWER';
      NO_LOAD_CHECK='Both';
      NO_IO_CHECK='Both';
      NO_ASSERT_CHECK='TRUE';
      NO_DIR_CHECK='TRUE';
      ALLOW_CONNECT='TRUE';
    'VDDQ1':
      PIN_NUMBER='(A9)';
      PINUSE='POWER';
      NO_LOAD_CHECK='Both';
      NO_IO_CHECK='Both';
      NO_ASSERT_CHECK='TRUE';
      NO_DIR_CHECK='TRUE';
      ALLOW_CONNECT='TRUE';
    'VDDQ2':
      PIN_NUMBER='(C1)';
      PINUSE='POWER';
      NO_LOAD_CHECK='Both';
      NO_IO_CHECK='Both';
      NO_ASSERT_CHECK='TRUE';
      NO_DIR_CHECK='TRUE';
      ALLOW_CONNECT='TRUE';
    'VDDQ3':
      PIN_NUMBER='(D9)';
      PINUSE='POWER';
      NO_LOAD_CHECK='Both';
      NO_IO_CHECK='Both';
      NO_ASSERT_CHECK='TRUE';
      NO_DIR_CHECK='TRUE';
      ALLOW_CONNECT='TRUE';
    'VDDQ4':
      PIN_NUMBER='(F2)';
      PINUSE='POWER';
      NO_LOAD_CHECK='Both';
      NO_IO_CHECK='Both';
      NO_ASSERT_CHECK='TRUE';
      NO_DIR_CHECK='TRUE';
      ALLOW_CONNECT='TRUE';
    'VDDQ5':
      PIN_NUMBER='(F8)';
      PINUSE='POWER';
      NO_LOAD_CHECK='Both';
      NO_IO_CHECK='Both';
      NO_ASSERT_CHECK='TRUE';
      NO_DIR_CHECK='TRUE';
      ALLOW_CONNECT='TRUE';
    'VDDQ6':
      PIN_NUMBER='(G1)';
      PINUSE='POWER';
      NO_LOAD_CHECK='Both';
      NO_IO_CHECK='Both';
      NO_ASSERT_CHECK='TRUE';
      NO_DIR_CHECK='TRUE';
      ALLOW_CONNECT='TRUE';
    'VDDQ7':
      PIN_NUMBER='(G9)';
      PINUSE='POWER';
      NO_LOAD_CHECK='Both';
      NO_IO_CHECK='Both';
      NO_ASSERT_CHECK='TRUE';
      NO_DIR_CHECK='TRUE';
      ALLOW_CONNECT='TRUE';
    'VDDQ8':
      PIN_NUMBER='(J2)';
      PINUSE='POWER';
      NO_LOAD_CHECK='Both';
      NO_IO_CHECK='Both';
      NO_ASSERT_CHECK='TRUE';
      NO_DIR_CHECK='TRUE';
      ALLOW_CONNECT='TRUE';
    'VDDQ9':
      PIN_NUMBER='(J8)';
      PINUSE='POWER';
      NO_LOAD_CHECK='Both';
      NO_IO_CHECK='Both';
      NO_ASSERT_CHECK='TRUE';
      NO_DIR_CHECK='TRUE';
      ALLOW_CONNECT='TRUE';
    'VPP0':
      PIN_NUMBER='(B1)';
      PINUSE='POWER';
      NO_LOAD_CHECK='Both';
      NO_IO_CHECK='Both';
      NO_ASSERT_CHECK='TRUE';
      NO_DIR_CHECK='TRUE';
      ALLOW_CONNECT='TRUE';
    'VPP1':
      PIN_NUMBER='(R9)';
      PINUSE='POWER';
      NO_LOAD_CHECK='Both';
      NO_IO_CHECK='Both';
      NO_ASSERT_CHECK='TRUE';
      NO_DIR_CHECK='TRUE';
      ALLOW_CONNECT='TRUE';
    'WE_N||A14':
      PIN_NUMBER='(L2)';
      INPUT_LOAD='(-0.01,0.01)';
    'ZQ':
      PIN_NUMBER='(F9)';
      PINUSE='POWER';
      NO_LOAD_CHECK='Both';
      NO_IO_CHECK='Both';
      NO_ASSERT_CHECK='TRUE';
      NO_DIR_CHECK='TRUE';
      ALLOW_CONNECT='TRUE';
    'DQL0':
      PIN_NUMBER='(G2)';
      BIDIRECTIONAL='TRUE';
      INPUT_LOAD='(-0.01,0.01)';
      OUTPUT_LOAD='(1.0,-1.0)';
    'DQL1':
      PIN_NUMBER='(F7)';
      BIDIRECTIONAL='TRUE';
      INPUT_LOAD='(-0.01,0.01)';
      OUTPUT_LOAD='(1.0,-1.0)';
    'DQL2':
      PIN_NUMBER='(H3)';
      BIDIRECTIONAL='TRUE';
      INPUT_LOAD='(-0.01,0.01)';
      OUTPUT_LOAD='(1.0,-1.0)';
    'DQL3':
      PIN_NUMBER='(H7)';
      BIDIRECTIONAL='TRUE';
      INPUT_LOAD='(-0.01,0.01)';
      OUTPUT_LOAD='(1.0,-1.0)';
    'DQL4':
      PIN_NUMBER='(H2)';
      BIDIRECTIONAL='TRUE';
      INPUT_LOAD='(-0.01,0.01)';
      OUTPUT_LOAD='(1.0,-1.0)';
    'DQL5':
      PIN_NUMBER='(H8)';
      BIDIRECTIONAL='TRUE';
      INPUT_LOAD='(-0.01,0.01)';
      OUTPUT_LOAD='(1.0,-1.0)';
    'DQL6':
      PIN_NUMBER='(J3)';
      BIDIRECTIONAL='TRUE';
      INPUT_LOAD='(-0.01,0.01)';
      OUTPUT_LOAD='(1.0,-1.0)';
    'DQL7':
      PIN_NUMBER='(J7)';
      BIDIRECTIONAL='TRUE';
      INPUT_LOAD='(-0.01,0.01)';
      OUTPUT_LOAD='(1.0,-1.0)';
    'DQU0':
      PIN_NUMBER='(A3)';
      BIDIRECTIONAL='TRUE';
      INPUT_LOAD='(-0.01,0.01)';
      OUTPUT_LOAD='(1.0,-1.0)';
    'DQU1':
      PIN_NUMBER='(B8)';
      BIDIRECTIONAL='TRUE';
      INPUT_LOAD='(-0.01,0.01)';
      OUTPUT_LOAD='(1.0,-1.0)';
    'DQU2':
      PIN_NUMBER='(C3)';
      BIDIRECTIONAL='TRUE';
      INPUT_LOAD='(-0.01,0.01)';
      OUTPUT_LOAD='(1.0,-1.0)';
    'DQU3':
      PIN_NUMBER='(C7)';
      BIDIRECTIONAL='TRUE';
      INPUT_LOAD='(-0.01,0.01)';
      OUTPUT_LOAD='(1.0,-1.0)';
    'DQU4':
      PIN_NUMBER='(C2)';
      BIDIRECTIONAL='TRUE';
      INPUT_LOAD='(-0.01,0.01)';
      OUTPUT_LOAD='(1.0,-1.0)';
    'DQU5':
      PIN_NUMBER='(C8)';
      BIDIRECTIONAL='TRUE';
      INPUT_LOAD='(-0.01,0.01)';
      OUTPUT_LOAD='(1.0,-1.0)';
    'DQU6':
      PIN_NUMBER='(D3)';
      BIDIRECTIONAL='TRUE';
      INPUT_LOAD='(-0.01,0.01)';
      OUTPUT_LOAD='(1.0,-1.0)';
    'DQU7':
      PIN_NUMBER='(D7)';
      BIDIRECTIONAL='TRUE';
      INPUT_LOAD='(-0.01,0.01)';
      OUTPUT_LOAD='(1.0,-1.0)';
    'CK_T':
      PIN_NUMBER='(K7)';
      INPUT_LOAD='(-0.01,0.01)';
    'CK_C':
      PIN_NUMBER='(K8)';
      INPUT_LOAD='(-0.01,0.01)';
    'DQSU_T':
      PIN_NUMBER='(B7)';
      BIDIRECTIONAL='TRUE';
      INPUT_LOAD='(-0.01,0.01)';
      OUTPUT_LOAD='(1.0,-1.0)';
    'DQSU_C':
      PIN_NUMBER='(A7)';
      BIDIRECTIONAL='TRUE';
      INPUT_LOAD='(-0.01,0.01)';
      OUTPUT_LOAD='(1.0,-1.0)';
    'DQSL_T':
      PIN_NUMBER='(G3)';
      BIDIRECTIONAL='TRUE';
      INPUT_LOAD='(-0.01,0.01)';
      OUTPUT_LOAD='(1.0,-1.0)';
    'DQSL_C':
      PIN_NUMBER='(F3)';
      BIDIRECTIONAL='TRUE';
      INPUT_LOAD='(-0.01,0.01)';
      OUTPUT_LOAD='(1.0,-1.0)';
    'TEN':
      PIN_NUMBER='(N9)';
      INPUT_LOAD='(-0.01,0.01)';
    'PAR':
      PIN_NUMBER='(T3)';
      INPUT_LOAD='(-0.01,0.01)';
    'VREFCA':
      PIN_NUMBER='(M1)';
      PINUSE='POWER';
      NO_LOAD_CHECK='Both';
      NO_IO_CHECK='Both';
      NO_ASSERT_CHECK='TRUE';
      NO_DIR_CHECK='TRUE';
      ALLOW_CONNECT='TRUE';
    'VSS0':
      PIN_NUMBER='(B2)';
      PINUSE='POWER';
      NO_LOAD_CHECK='Both';
      NO_IO_CHECK='Both';
      NO_ASSERT_CHECK='TRUE';
      NO_DIR_CHECK='TRUE';
      ALLOW_CONNECT='TRUE';
    'VSS1':
      PIN_NUMBER='(E1)';
      PINUSE='POWER';
      NO_LOAD_CHECK='Both';
      NO_IO_CHECK='Both';
      NO_ASSERT_CHECK='TRUE';
      NO_DIR_CHECK='TRUE';
      ALLOW_CONNECT='TRUE';
    'VSS2':
      PIN_NUMBER='(E9)';
      PINUSE='POWER';
      NO_LOAD_CHECK='Both';
      NO_IO_CHECK='Both';
      NO_ASSERT_CHECK='TRUE';
      NO_DIR_CHECK='TRUE';
      ALLOW_CONNECT='TRUE';
    'VSS3':
      PIN_NUMBER='(G8)';
      PINUSE='POWER';
      NO_LOAD_CHECK='Both';
      NO_IO_CHECK='Both';
      NO_ASSERT_CHECK='TRUE';
      NO_DIR_CHECK='TRUE';
      ALLOW_CONNECT='TRUE';
    'VSS4':
      PIN_NUMBER='(K1)';
      PINUSE='POWER';
      NO_LOAD_CHECK='Both';
      NO_IO_CHECK='Both';
      NO_ASSERT_CHECK='TRUE';
      NO_DIR_CHECK='TRUE';
      ALLOW_CONNECT='TRUE';
    'VSS5':
      PIN_NUMBER='(K9)';
      PINUSE='POWER';
      NO_LOAD_CHECK='Both';
      NO_IO_CHECK='Both';
      NO_ASSERT_CHECK='TRUE';
      NO_DIR_CHECK='TRUE';
      ALLOW_CONNECT='TRUE';
    'VSS6':
      PIN_NUMBER='(M9)';
      PINUSE='POWER';
      NO_LOAD_CHECK='Both';
      NO_IO_CHECK='Both';
      NO_ASSERT_CHECK='TRUE';
      NO_DIR_CHECK='TRUE';
      ALLOW_CONNECT='TRUE';
    'VSS7':
      PIN_NUMBER='(N1)';
      PINUSE='POWER';
      NO_LOAD_CHECK='Both';
      NO_IO_CHECK='Both';
      NO_ASSERT_CHECK='TRUE';
      NO_DIR_CHECK='TRUE';
      ALLOW_CONNECT='TRUE';
    'VSS8':
      PIN_NUMBER='(T1)';
      PINUSE='POWER';
      NO_LOAD_CHECK='Both';
      NO_IO_CHECK='Both';
      NO_ASSERT_CHECK='TRUE';
      NO_DIR_CHECK='TRUE';
      ALLOW_CONNECT='TRUE';
    'VSSQ0':
      PIN_NUMBER='(A2)';
      PINUSE='POWER';
      NO_LOAD_CHECK='Both';
      NO_IO_CHECK='Both';
      NO_ASSERT_CHECK='TRUE';
      NO_DIR_CHECK='TRUE';
      ALLOW_CONNECT='TRUE';
    'VSSQ1':
      PIN_NUMBER='(A8)';
      PINUSE='POWER';
      NO_LOAD_CHECK='Both';
      NO_IO_CHECK='Both';
      NO_ASSERT_CHECK='TRUE';
      NO_DIR_CHECK='TRUE';
      ALLOW_CONNECT='TRUE';
    'VSSQ2':
      PIN_NUMBER='(C9)';
      PINUSE='POWER';
      NO_LOAD_CHECK='Both';
      NO_IO_CHECK='Both';
      NO_ASSERT_CHECK='TRUE';
      NO_DIR_CHECK='TRUE';
      ALLOW_CONNECT='TRUE';
    'VSSQ3':
      PIN_NUMBER='(D2)';
      PINUSE='POWER';
      NO_LOAD_CHECK='Both';
      NO_IO_CHECK='Both';
      NO_ASSERT_CHECK='TRUE';
      NO_DIR_CHECK='TRUE';
      ALLOW_CONNECT='TRUE';
    'VSSQ4':
      PIN_NUMBER='(D8)';
      PINUSE='POWER';
      NO_LOAD_CHECK='Both';
      NO_IO_CHECK='Both';
      NO_ASSERT_CHECK='TRUE';
      NO_DIR_CHECK='TRUE';
      ALLOW_CONNECT='TRUE';
    'VSSQ5':
      PIN_NUMBER='(E3)';
      PINUSE='POWER';
      NO_LOAD_CHECK='Both';
      NO_IO_CHECK='Both';
      NO_ASSERT_CHECK='TRUE';
      NO_DIR_CHECK='TRUE';
      ALLOW_CONNECT='TRUE';
    'VSSQ6':
      PIN_NUMBER='(E8)';
      PINUSE='POWER';
      NO_LOAD_CHECK='Both';
      NO_IO_CHECK='Both';
      NO_ASSERT_CHECK='TRUE';
      NO_DIR_CHECK='TRUE';
      ALLOW_CONNECT='TRUE';
    'VSSQ7':
      PIN_NUMBER='(F1)';
      PINUSE='POWER';
      NO_LOAD_CHECK='Both';
      NO_IO_CHECK='Both';
      NO_ASSERT_CHECK='TRUE';
      NO_DIR_CHECK='TRUE';
      ALLOW_CONNECT='TRUE';
    'VSSQ8':
      PIN_NUMBER='(H1)';
      PINUSE='POWER';
      NO_LOAD_CHECK='Both';
      NO_IO_CHECK='Both';
      NO_ASSERT_CHECK='TRUE';
      NO_DIR_CHECK='TRUE';
      ALLOW_CONNECT='TRUE';
    'VSSQ9':
      PIN_NUMBER='(H9)';
      PINUSE='POWER';
      NO_LOAD_CHECK='Both';
      NO_IO_CHECK='Both';
      NO_ASSERT_CHECK='TRUE';
      NO_DIR_CHECK='TRUE';
      ALLOW_CONNECT='TRUE';
    '-DML_N||DBIL':
      PIN_NUMBER='(E7)';
      BIDIRECTIONAL='TRUE';
      INPUT_LOAD='(-0.01,0.01)';
      OUTPUT_LOAD='(1.0,-1.0)';
    '-DMU_N||DBIU':
      PIN_NUMBER='(E2)';
      BIDIRECTIONAL='TRUE';
      INPUT_LOAD='(-0.01,0.01)';
      OUTPUT_LOAD='(1.0,-1.0)';
    '-RESET':
      PIN_NUMBER='(P1)';
      INPUT_LOAD='(-0.01,0.01)';
  end_pin;
  body
    PART_NAME='K4A8G165WCBCTD';
    BODY_NAME='K4A8G165WCBCTD';
    PHYS_DES_PREFIX='U';
    CLASS='IC';
  end_body;
end_primitive;

END.
